# HONEY BADGER DPB LOW LOSS GCE(D)-1A BOM of 55.B0707.D06G.xlsx — HONEY BADGER DPB LOW LOSS GCE(D (bom)
| Level | Parent Number | Part Number | Description | Green Factor | Life Cycle State | Manufacturer | Manufacturer Part Number | Source | BOM Usage | M/P Code | S/D | Qty | UoM | Location |
| 1 | 55.B0707.D06G | 55.B0707.S06G | HONEY BADGER DPB LOW LOSS GCE(S)-1A | N/A; | Released |  |  |  | E | Manufacture | DIP | 1 | PCS |  |
| 2 | 55.B0707.S06G | 020.F0274.0029 | CONN CTR SMD S14+P15 C20202-12933-L,LCP | R2_SA; | Released | ALLTOP | C20202-12933-L | Single |  | Purchase | SMT | 15 | PCS | SKT1 SKT10 SKT11 SKT12 SKT13 SKT14 SKT15 SKT2 SKT3 SKT4 SKT5 SKT6 SKT7 SKT8 SKT9 |
| 2 | 55.B0707.S06G | 083.55130.008F | DIODE S.B RB551V30 SOD-323 | R2_SA;HF_SA; | Released | YEASHIN | RB551V30 | Single |  | Purchase | SMT | 15 | PCS | D15 D16 D17 D18 D19 D20 D21 D23 D24 D25 D26 D27 D28 D29 D30 |
| 2 | 55.B0707.S06G | 20.C0093.164 | CONN EDGE SMD 164P G630HAA12246EU PCIE | R2_SA; | Released | AMPHENOL | G630HAA12246EU | Single |  | Purchase | SMT | 2 | PCS | CN1 CN2 |
| 2 | 55.B0707.S06G | 20.C0094.036 | CONN EDGE SMD 36P G630H3612246EU PCIE | R2_SA; | Released | AMPHENOL | G630H3612246EU | Single |  | Purchase | SMT | 4 | PCS | CN5 CN6 CN8 CN9 |
| 2 | 55.B0707.S06G | 20.F2288.060 | CONN CTR SMD 36P+24S GPCE54362413HR,PA4T | R2_SA; | Released | AMPHENOL | GPCE54362413HR | Single |  | Purchase | SMT | 1 | PCS | CN7 |
| 2 | 55.B0707.S06G | 48.B0743.01A | PCB 14545-1A HONEY BADGER LOW LOS 8L GCE | R2_C; | Released | GCE |  | Single |  | Purchase | SMT | 1 | PCS |  |
| 2 | 55.B0707.S06G | 63.00000.00L | CHIP RES 0 J 1/10W 0603 | R2_SA;HF_SA;G_SA; | Released | TA-I ; RALEC ; YAGEO ; WALSIN | RM06JTN0 ; RTT03000JTP ; RC0603JR-070RL ; WR06X000PTL | Multiple |  | Purchase | SMT | 7 | PCS | PR1 PR19 PR24 PR35 PR4 PR54 R486 |
| 2 | 55.B0707.S06G | 63.10134.1DL | CHIP RES 100 J 1/16W 0402 | R2_SA;HF_SA;G_SA; | Released | TA-I;RALEC;CYNTEC;YAGEO;WALSIN | RM04JTN101 ; RTT02101JTH ; RR0510S-101-JN ; RC0402JR-07100RL;WR04X101JTL | Multiple |  | Purchase | SMT | 2 | PCS | R358 R407 |
| 2 | 55.B0707.S06G | 63.2R037.18L | CHIP RES 2 J 1/2W 2010 | R2_SA;HF_SA;G_SA; | Released | TAI;RALEC | RM20JEN2R0;RTT202R0JTE | Multiple |  | Purchase | SMT | 34 | PCS | R100 R110 R121 R124 R134 R138 R151 R154 R161 R163 R175 R178 R190 R195 R205 R209 R218 R223 R234 R236 R245 R250 R260 R264 R273 R276 R289 R292 R302 R304 R542 R607 R608 R609 |
| 2 | 55.B0707.S06G | 63.47234.1DL | CHIP RES 4.7K J 1/16W 0402 | R2_SA;HF_SA;G_SA; | Released | TA-I;RALEC;CYNTEC;YAGEO;WALSIN | RM04JTN472 ; RTT02472JTH ; RR0510S-472-JN ; RC0402JR-074K7L;WR04X472JTL | Multiple |  | Purchase | SMT | 110 | PCS | R106 R108 R120 R123 R133 R136 R148 R150 R162 R165 R176 R180 R189 R193 R203 R204 R217 R221 R232 R235 R246 R248 R261 R262 R274 R278 R290 R291 R301 R306 R311 R317 R321 R322 R323 R324 R329 R332 R333 R336 R338 R339 R345 R349 R350 R367 R368 R371 R372 R381 R422 R423 R424 R425 R426 R427 R428 R429 R430 R431 R432 R433 R434 R435 R436 R437 R438 R439 R440 R441 R442 R443 R444 R445 R446 R447 R448 R449 R450 R451 R452 R453 R454 R455 R456 R457 R458 R459 R460 R461 R462 R463 R464 R465 R466 R467 R468 R469 R470 R471 R472 R473 R474 R475 R476 R477 R494 R495 R505 R506 |
| 2 | 55.B0707.S06G | 63.R0034.1DL | CHIP RES 0 J 1/16W 0402 | R2_SA;HF_SA;G_SA; | Released | TA-I;RALEC;CYNTEC;YAGEO;WALSIN | RM04JTN0;RTT02000JTH;RR0510X-000-XN;RC0402JR-070RL;WR04X000PTL | Multiple |  | Purchase | SMT | 132 | PCS | PR15 PR16 PR18 PR28 PR32 PR34 PR44 PR48 PR7 R103 R105 R112 R113 R116 R118 R126 R127 R130 R132 R140 R141 R144 R146 R153 R155 R158 R160 R168 R169 R172 R174 R182 R183 R186 R188 R196 R197 R200 R202 R210 R211 R214 R216 R224 R225 R228 R230 R238 R239 R242 R244 R252 R253 R256 R258 R266 R267 R270 R272 R280 R281 R284 R286 R294 R295 R298 R300 R308 R309 R310 R314 R318 R319 R326 R330 R334 R335 R343 R351 R352 R353 R354 R357 R360 R361 R365 R369 R373 R374 R376 R378 R379 R380 R382 R384 R386 R391 R392 R393 R394 R396 R398 R400 R402 R404 R408 R409 R410 R411 R412 R413 R414 R415 R416 R417 R418 R419 R420 R421 R480 R481 R507 R508 R509 R510 R511 R544 R545 R546 R547 R548 R549 |
| 2 | 55.B0707.S06G | 64.10015.6DL | CHIP RES 1K F 1/16W 0402 | R2_SA;HF_SA;G_SA; | Released | TA-I;RALEC;CYNTEC;YAGEO;WALSIN | RM04FTN1001 ; RTT021001FTH ; RR0510S-102-FN ; RC0402FR-071KL;WR04X1001FTL | Multiple |  | Purchase | SMT | 15 | PCS | R488 R489 R490 R491 R492 R493 R496 R497 R498 R499 R500 R501 R502 R503 R504 |
| 2 | 55.B0707.S06G | 64.10025.6DL | CHIP RES 10K F 1/16W 0402 | R2_SA;HF_SA;G_SA; | Released | TA-I;RALEC;CYNTEC;YAGEO;WALSIN | RM04FTN1002 ; RTT021002FTH ; RR0510S-103-FN ; RC0402FR-0710KL;WR04X1002FTL | Multiple |  | Purchase | SMT | 47 | PCS | PR2 PR23 PR25 PR39 PR41 PR49 PR5 PR50 PR51 R101 R114 R128 R142 R156 R170 R184 R198 R212 R226 R240 R254 R268 R282 R296 R342 R344 R356 R363 R366 R370 R375 R377 R383 R385 R387 R388 R390 R395 R397 R399 R401 R403 R405 R482 R483 R484 R485 |
| 2 | 55.B0707.S06G | 64.10026.6DL | CHIP RES 10K D 1/16W 0402 | R2_SA;HF_SA;G_SA; | Released | CYNTEC;RALEC;TA-I;WALSIN;YAGEO | RR0510Q-103-DN;RTT021002DTH;RM04DTN1002;WF04H1002DTL;RT0402DRE0710KL | Multiple |  | Purchase | SMT | 3 | PCS | PR14 PR27 PR43 |
| 2 | 55.B0707.S06G | 64.10035.6DL | CHIP RES 100K F 1/16W 0402 | R2_SA;HF_SA;G_SA; | Released | TA-I;RALEC;CYNTEC;YAGEO;WALSIN | RM04FTN1003 ; RTT021003FTH ; RR0510S-104-FN ; RC0402FR-07100KL;WR04X1003FTL | Multiple |  | Purchase | SMT | 4 | PCS | PR10 PR26 PR42 PR55 |
| 2 | 55.B0707.S06G | 64.10R05.6DL | CHIP RES 10 F 1/16W 0402 | R2_SA;HF_SA;G_SA; | Released | TA-I ; RALEC ; CYNTEC ; YAGEO | RM04FTN10R0 ; RTT0210R0FTH ; RR0510S-100-FN ; RC0402FR-0710RL | Multiple |  | Purchase | SMT | 3 | PCS | PR21 PR37 PR6 |
| 2 | 55.B0707.S06G | 64.11535.6DL | CHIP RES 115K F 1/16W 0402 | R2_SA;HF_SA;G_SA; | Released | YAGEO;CYNTEC;TAI;RALEC;WALSIN | RC0402FR-07115KL;RR0510S-1153-FN;RM04FTN1153;RTT021153FTH ;WR04X1153FTL | Multiple |  | Purchase | SMT | 3 | PCS | PR13 PR30 PR46 |
| 2 | 55.B0707.S06G | 64.20015.6DL | CHIP RES 2K F 1/16W 0402 | R2_SA;HF_SA;G_SA; | Released | TA-I;RALEC;CYNTEC;YAGEO;WALSIN | RM04FTN2001 ; RTT022001FTH ; RR0510S-202-FN ; RC0402FR-072KL;WR04X2001FTL | Multiple |  | Purchase | SMT | 1 | PCS | R389 |
| 2 | 55.B0707.S06G | 64.20035.6DL | CHIP RES 200K F 1/16W 0402 | R2_SA;HF_SA;G_SA; | Released | TA-I;RALEC;CYNTEC;YAGEO;WALSIN | RM04FTN2003 ; RTT022003FTH ; RR0510S-204-FN ; RC0402FR-07200KL;WR04X2003FTL | Multiple |  | Purchase | SMT | 30 | PCS | R109 R122 R137 R149 R166 R181 R194 R207 R222 R233 R249 R263 R275 R288 R307 R478 R479 R550 R551 R552 R553 R554 R555 R556 R557 R558 R559 R560 R561 R562 |
| 2 | 55.B0707.S06G | 64.20045.6DL | CHIP RES 2M F 1/16W 0402 | R2_SA;HF_SA;G_SA; | Released | TA-I;RALEC;CYNTEC;YAGEO | RM04FTN2004;RTT022004FTH;RR0510S-2004-FN;RC0402FR-072ML | Multiple |  | Purchase | SMT | 1 | PCS | PR52 |
| 2 | 55.B0707.S06G | 64.22005.55L | CHIP RES 220 F 1/10W 0603 | R2_SA;HF_SA;G_SA; | Released | TA-I ; RALEC ; YAGEO | RM06FTN2200 ; RTT032200FTP ; RC0603FR-07220RL | Multiple |  | Purchase | SMT | 15 | PCS | R111 R125 R139 R152 R167 R177 R191 R208 R219 R237 R251 R265 R279 R293 R303 |
| 2 | 55.B0707.S06G | 64.22125.55L | CHIP RES 22.1K F 1/10W 0603 | R2_SA;HF_SA;G_SA; | Released | TA-I ; RALEC ; YAGEO | RM06FTN2212 ; RTT032212FTP ; RC0603FR-0722K1L | Multiple |  | Purchase | SMT | 1 | PCS | PR56 |
| 2 | 55.B0707.S06G | 64.24915.6DL | CHIP RES 2.49K F 1/16W 0402 | R2_SA;HF_SA;G_SA; | Released | TA-I;RALEC;CYNTEC;YAGEO;WALSIN | RM04FTN2491;RTT022491FTH;RR0510S-2491-FN;RC0402FR-072K49L;WR04X2491FTL | Multiple |  | Purchase | SMT | 3 | PCS | PR17 PR3 R487 |
| 2 | 55.B0707.S06G | 64.30035.6DL | CHIP RES 300K F 1/16W 0402 | R2_SA;HF_SA;G_SA; | Released | TA-I;RALEC;CYNTEC;YAGEO;WALSIN | RM04FTN3003;RTT023003FTH;RR0510S-304-FN;RC0402FR-07300KL;WR04X3003FTL | Multiple |  | Purchase | SMT | 15 | PCS | R563 R564 R565 R566 R567 R568 R569 R570 R571 R572 R573 R574 R575 R576 R577 |
| 2 | 55.B0707.S06G | 64.33005.6DL | CHIP RES 330 F 1/16W 0402 | R2_SA;HF_SA;G_SA; | Released | CYNTEC;RALEC;TAI;YAGEO | RR0510S-331-FN;RTT023300FTH;RM04FTN3300;RC0402FR-07330RL | Multiple |  | Purchase | SMT | 15 | PCS | R104 R117 R131 R145 R159 R173 R187 R201 R215 R229 R243 R257 R271 R285 R299 |
| 2 | 55.B0707.S06G | 64.40205.6DL | CHIP RES 402 F 1/16W 0402 | R2_SA;HF_SA;G_SA; | Released | TA-I;RALEC;CYNTEC;YAGEO | RM04FTN4020;RTT024020FTH;RR0510S-4020-FN;RC0402FR-07402RL | Multiple |  | Purchase | SMT | 15 | PCS | R102 R115 R129 R143 R157 R171 R185 R199 R213 R227 R241 R255 R269 R283 R297 |
| 2 | 55.B0707.S06G | 64.47035.6DL | CHIP RES 470K F 1/16W 0402 | R2_SA;HF_SA;G_SA; | Released | TA-I;RALEC;CYNTEC;YAGEO;WALSIN | RM04FTN4703;RTT024703FTH;RR0510S-474-FN;RC0402FR-07470KL;WR04X4703FTL | Multiple |  | Purchase | SMT | 1 | PCS | PR53 |
| 2 | 55.B0707.S06G | 64.73225.6DL | CHIP RES 73.2K F 1/16W 0402 | R2_SA;HF_SA;G_SA; | Released | TA-I;RALEC;CYNTEC;YAGEO;WALSIN | RM04FTN7322;RTT027322FTH;RR0510S-7322-FN;RC0402FR-0773K2L;WR04X7322FTL | Multiple |  | Purchase | SMT | 3 | PCS | PR11 PR29 PR45 |
| 2 | 55.B0707.S06G | 68.00084.771 | CHIP BEAD BLM41PG600SN1L MURAT | R2_SA; | Released | MURATA | BLM41PG600SN1L | Single |  | Purchase | SMT | 3 | PCS | PL1 PL3 PL5 |
| 2 | 55.B0707.S06G | 68.2201D.10J | CHIP IND 22UH #A921CY-220M=P3 | R2_SA; | Released | TOKO | #A921CY-220M=P3 | Single |  | Purchase | SMT | 1 | PCS | PL7 |
| 2 | 55.B0707.S06G | 68.4R71A.20Q | CHIP CHOKE 4.7UH M PCMB104T-4R7MS | R2_SA; | Released | CYNTEC | PCMB104T-4R7MS | Single |  | Purchase | SMT | 3 | PCS | PL2 PL4 PL6 |
| 2 | 55.B0707.S06G | 72.02464.00Q | IC EPROM 24LC64T-I/STG TSSOP8P | R2_SA; | Released | MICROCHIP | 24LC64T-I/STG | Single |  | Purchase | SMT | 1 | PCS | U50 |
| 2 | 55.B0707.S06G | 73.01G08.L03 | IC CMOS SN74LVC1G08DCKR SC-70 | R2_SA;HF_SA;G_SA; | Released | TI | SN74LVC1G08DCKR | Single |  | Purchase | SMT | 30 | PCS | U1 U10 U12 U13 U15 U16 U18 U19 U21 U22 U24 U25 U27 U28 U3 U30 U31 U33 U34 U36 U37 U39 U4 U40 U42 U43 U45 U6 U7 U9 |
| 2 | 55.B0707.S06G | 74.00075.B79 | IC TEMP SENSOR TMP75AIDGKR MSOP 8P | R2_SA; | Released | TI | TMP75AIDGKR | Single |  | Purchase | SMT | 4 | PCS | U46 U47 U48 U49 |
| 2 | 55.B0707.S06G | 74.01015.049 | IC CONV ADS1015IDGSR MSOP 10P | R2_SA; | Released | TI | ADS1015IDGSR | Single |  | Purchase | SMT | 1 | PCS | U53 |
| 2 | 55.B0707.S06G | 74.08201.04P | IC DC/DC REGULATOR SY8201ABC SOT23-6 | R2_SA;HF_SA; | Released | SILERGY | SY8201ABC | Single |  | Purchase | SMT | 1 | PCS | U54 |
| 2 | 55.B0707.S06G | 74.53319.073 | IC PWR CTRL TPS53319DQPR QFN 22P | R2_SA;HF_SA; | Released | TI | TPS53319DQPR | Single |  | Purchase | SMT | 3 | PCS | PU1 PU2 PU3 |
| 2 | 55.B0707.S06G | 77.21561.00L | CHIP CAP POS 15U 25V 25TQC15M | R2_SA;HF_SA;G_SA; | Released | SANYO | 25TQC15M | Single |  | Purchase | SMT | 2 | PCS | TC1 TC2 |
| 2 | 55.B0707.S06G | 77.23371.061 | CHIP CAP POS 330U 10V D4 10TPB | R2_SA;HF_SA; | Released | SANYO | 10TPB330M | Single |  | Purchase | SMT | 6 | PCS | PTC1 PTC2 PTC3 PTC4 PTC5 PTC6 |
| 2 | 55.B0707.S06G | 78.10324.2FL | CHIP CAP C 0.01U 50V K0402 X7R | R2_SA;HF_SA;G_SA; | Released | MURATA;PHYCOMP;DARFON;TDK;SAMSUNG;WALSIN;MURATA | GRM155R71H103KA88D;223858715636;C1005X7R103KGT;C1005X7R1H103KT;CL05B103KB5NNNC;0402B103K500CT;WBM155R71H103KA01D | Multiple |  | Purchase | SMT | 75 | PCS | C100 C103 C104 C105 C108 C118 C119 C120 C121 C131 C134 C135 C136 C137 C147 C150 C151 C152 C153 C156 C166 C167 C168 C169 C178 C182 C183 C184 C185 C190 C198 C199 C200 C201 C204 C214 C215 C216 C217 C222 C230 C231 C232 C233 C238 C246 C247 C248 C249 C254 C262 C263 C264 C265 C270 C278 C279 C280 C281 C286 C294 C295 C296 C297 C303 C310 C311 C312 C313 C323 C326 C327 C328 C329 C332 |
| 2 | 55.B0707.S06G | 78.10421.2FL | CHIP CAP C 0.1U 16V K0402 X7R | R2_SA;HF_SA;G_SA; | Released | DARFON;MURATA;PHYCOMP;SAMSUNG;TAIYO;TDK;WALSIN;YAGEO | C1005X7R104KET;GRM155R71C104KA88D;223878715649;CL05B104KO5NNNC;EMK105BJ104KV-FR ;C1005X7R1C104KT000F;0402B104K160CT;CC0402KRX7R7BB104 | Multiple |  | Purchase | SMT | 6 | PCS | C352 C353 C354 C361 C362 PC41 |
| 2 | 55.B0707.S06G | 78.10422.2BL | CHIP CAP C 0.1U 25V K0603 X7R | R2_SA;HF_SA;G_SA; | Released | AVX;DARFON;MURATA;PHYCOMP;SAMSUNG;TAIYO;TDK;WALSIN;YAGEO | 06033C104KAT2A;C1608X7R104KFT;GRM188R71E104KA01D;223891615649;CL10B104KA8NNNC;TMK107BJ104KA-T;C1608X7R1E104KT;0603B104K250CT;CC0603KRX7R8BB104 | Multiple |  | Purchase | SMT | 1 | PCS | PC44 |
| 2 | 55.B0707.S06G | 78.10422.5FL | CHIP CAP C 0.1U 25V K0402 X5R | R2_SA;HF_SA;G_SA; | Released | MURATA;YAGEO;TDK;TAIYO;SAMSUNG;WALSIN;DARFON | GRM155R61E104KA87D;CC0402KRX5R8BB104;C1005X5R1E104KT000E;TMK105BJ104KV-F;CL05A104KA5NNNC;0402X104K250CT;C1005X5R104KFT | Multiple |  | Purchase | SMT | 6 | PCS | PC15 PC21 PC28 PC34 PC7 PC8 |
| 2 | 55.B0707.S06G | 78.10423.2FL | CHIP CAP C 0.1U 10V K0402 X7R | R2_SA;HF_SA;G_SA; | Released | MURATA;PHYCOMP;SAMSUNG;TAIYO;TDK;DARFON;WALSIN;MURATA;YAGEO | GRM155R71A104KA01D;223824715649;CL05B104KP5NNNC;RMLMK105BJ104KV-F;C1005X7R1A104KT000F;C1005X7R104KDT;0402B104K100CT;WBM155R71A104KA01D;CC0402KRX7R6BB104 | Multiple |  | Purchase | SMT | 34 | PCS | C102 C110 C117 C125 C133 C141 C149 C158 C165 C171 C181 C187 C197 C203 C213 C219 C229 C235 C245 C253 C261 C269 C277 C283 C293 C301 C309 C315 C324 C339 C340 C341 C342 C343 |
| 2 | 55.B0707.S06G | 78.10424.2BL | CHIP CAP C 0.1U 50V K0603 X7R | R2_SA;HF_SA;G_SA; | Released | MURATA;TDK;AVX;PHYCOMP;SAMSUNG;DARFON;MATSUKI;WALSIN | GRM188R71H104KA93D;C1608X7R1H104KT000N;06035C104KAT2A;223858615649;CL10B104KB8NNNC;C1608X7R104KGT;MAG03X7R1H104K;0603B104K500CT | Multiple |  | Purchase | SMT | 1 | PCS | C347 |
| 2 | 55.B0707.S06G | 78.10521.2BL | CHIP CAP C 1U 16V K0603 X7R | R2_SA;HF_SA;G_SA; | Released | KEMET;MURATA;TAIYO;TDK;PHYCOMP;WALSIN;SAMSUNG;DARFON | C0603C105K4RAC;GRM188R71C105KA12D;EMK107B7105KA-T;C1608X7R1C105KT;223878615663;0603B105K160CT;CL10B105KO8NNNC;C1608X7R105KET | Multiple |  | Purchase | SMT | 16 | PCS | C106 C122 C138 C154 C172 C188 C205 C220 C236 C250 C266 C284 C298 C316 C330 C346 |
| 2 | 55.B0707.S06G | 78.10522.5BL | CHIP CAP C 1U 25V K0603 X5R | R2_SA;HF_SA;G_SA; | Released | MURATA;TDK;PHYCOMP;TAIYO;MATSUKI;DARFON;TDK;WALSIN;SAMSUNG;YAGEO | GRM188R61E105KA12D;C1608X5R1E105KT000N;223891613663;TMK107BJ105KA-T;MAG03X5R1E105K;C1608X5R105KFT;C1608X5R1E105KT000N;0603X105K250CT;CL10A105KA8NNNC;CC0603KRX5R8BB105 | Multiple |  | Purchase | SMT | 19 | PCS | C115 C124 C130 C132 C146 C148 C157 C163 C179 C195 C211 C227 C243 C259 C272 C291 C307 C322 C338 |
| 2 | 55.B0707.S06G | 78.10523.5FL | CHIP CAP C 1U 10V K0402 X5R | R2_SA;HF_SA;G_SA; | Released | MURATA;TDK;DARFON;MATSUKI;PHYCOMP;TAIYO;SAMSUNG;WALSIN | GRM155R61A105KE15D;C1005X5R1A105KT;C1005X5R105KDT;MAG02X5R1A105K;223824713663;LMK105BJ105KVF;CL05A105KP5NNNC;0402X105K100CT | Multiple |  | Purchase | SMT | 4 | PCS | C363 PC10 PC17 PC30 |
| 2 | 55.B0707.S06G | 78.10621.22L | CHIP CAP C 10U 16V K1206 X7R | R2_SA;HF_SA;G_SA; | Released | MURATA;TDK;AVX;DARFON;SAMSUNG;TAIYO | GRM31CR71C106KA12L;C3216X7R1C106KT;CM316X7R106K16AT;C3216X7R106KEP;CL31B106KOHNNNE;EMK316B7106KL-T | Multiple |  | Purchase | SMT | 21 | PCS | C107 C123 C139 C155 C173 C189 C206 C221 C237 C251 C267 C285 C299 C317 C331 PC11 PC12 PC25 PC26 PC38 PC39 |
| 2 | 55.B0707.S06G | 78.10622.51L | CHIP CAP C 10U 25V K0805 X5R | R2_SA;HF_SA;G_SA; | Released | MATSUKI;SAMSUNG;TAIYO;AVX;MURATA;TDK;YAGEO | MAG05X5R1E106K;CL21A106KAYNNNE;TMK212BJ106KG-TD;CM21X5R106K25AT;GRM21BR61E106KA73L;C2012X5R1E106KT;CC0805KKX5R8BB106 | Multiple |  | Purchase | SMT | 2 | PCS | C350 C351 |
| 2 | 55.B0707.S06G | 78.10622.52L | CHIP CAP C 10U 25V K1206 X5R | R2_SA;HF_SA;G_SA; | Released | TAIYO;MURATA;AVX;TDK;KEMET;MATSUKI;PHYCOMP;DARFON;SAMSUNG | TMK316BJ106KL-T;GRM31CR61E106KA12L;12063D106KAT2A;C3216X5R1E106KT;C1206C106K3PAC;MAG06X5R1E106K;222291113676;C3216X5R106KFP;CL31A106KAHNNNE | Multiple |  | Purchase | SMT | 62 | PCS | C111 C112 C113 C114 C126 C127 C128 C129 C142 C143 C144 C145 C159 C160 C161 C162 C174 C175 C176 C177 C191 C192 C193 C194 C207 C208 C209 C210 C223 C224 C225 C226 C239 C240 C241 C242 C255 C256 C257 C258 C271 C273 C274 C275 C287 C288 C289 C290 C302 C304 C305 C306 C318 C319 C320 C321 C333 C334 C335 C336 C348 C349 |
| 2 | 55.B0707.S06G | 78.22034.1BL | CHIP CAP 22P50V J0603 NPO(ROHS | R2_SA;HF_SA;G_SA; | Released | PHYCOMP;MURATA;AVX;TDK;SAMSUNG;DARFON;WALSIN | 223886715229;GRM1885C1H220JA01D;06035A220JAT2A;C1608C0G1H220JT;CL10C220JB8NNNC;C1608NPO220JGT;0603N220J500LT | Multiple |  | Purchase | SMT | 1 | PCS | PC42 |
| 2 | 55.B0707.S06G | 78.22611.52L | CHIP CAP 22U 16V M1206 X5R | R2_SA;HF_SA;G_SA; | Released | MURATA;TAIYO;AVX;SAMSUNG | GRM31CR61C226ME15L;EMK316BJ226ML-T;CM316X5R226M16AT;CL31A226KOHNNNE | Multiple |  | Purchase | SMT | 1 | PCS | PC43 |
| 2 | 55.B0707.S06G | 78.22612.51L | CHIP CAP C 22U 25V M0805 X5R | R2_SA;HF_SA;G_SA; | Released | MURATA;SANSUNG;DARFON;TDK | GRM21BR61E226ME44L;CL21A226MAQNNNE;C2012X5R226MFP;C2012X5R1E226MT | Multiple |  | Purchase | SMT | 19 | PCS | PC1 PC14 PC16 PC18 PC2 PC22 PC24 PC27 PC29 PC3 PC31 PC35 PC37 PC4 PC46 PC47 PC5 PC68 PC69 |
| 2 | 55.B0707.S06G | 78.33322.2FL | CHIP CAP C 0.033U 25V K0402 X7 | R2_SA;HF_SA;G_SA; | Released | MURATA ; TDK ; KEMET; WALSIN | GRM155R71E333KA88D ; C1005X7R1E333KT000F ; C0402C333K3RACTU; 0402B333K250CT | Multiple |  | Purchase | SMT | 30 | PCS | C364 C365 C366 C367 C368 C369 C370 C371 C372 C373 C374 C375 C376 C377 C378 C379 C380 C381 C382 C383 C384 C385 C386 C387 C388 C389 C390 C391 C392 C393 |
| 2 | 55.B0707.S06G | 78.47522.51L | CHIP CAP C 4.7U 25V K0805 X5R | R2_SA;HF_SA;G_SA; | Released | MURATA;AVX;TAIYO;MATSUKI;TDK;SAMSUNG;PHYCOMP | GRM21BR61E475KA12L;CM21X5R475K25AT;TMK212BJ475KG-T;MAG05X5R1E475K;C2012X5R1E475KT50HN;CL21A475KAQNNNE;222291013672 | Multiple |  | Purchase | SMT | 3 | PCS | PC23 PC36 PC6 |
| 2 | 55.B0707.S06G | 78.47524.L2L | CHIP CAP C 4.7UF 50V K1206 X5R T=0.9 | R2_SA;HF_SA;G_SA; | Released | MURATA;SAMSUNG;TAIYO | GRM319R61H475KA12D;CL31A475KB9LNNC;UMK316BJ475KD-T | Multiple |  | Purchase | SMT | 1 | PCS | PC40 |
| 2 | 55.B0707.S06G | 78.68124.2FL | CHIP CAP C 680P 50V K0402 X7R | R2_SA;HF_SA;G_SA; | Released | AVX;DARFON;MURATA;PHYCOMP;TAIYO;TDK;WALSIN | CM05X7R681K50AT;C1005X7R681KGT;GRM155R71H681KA01D;223858715621;UMK105BJ681KV-F;C1005X7R1H681KT;0402B681K500CT | Multiple |  | Purchase | SMT | 3 | PCS | PC13 PC19 PC32 |
| 2 | 55.B0707.S06G | 83.19226.C70 | LED R/B 19-226/R6BHC-B01/2T SM | R2_SA; | Released | EVERLIGHT | 19-226/R6BHC-B01/2T | Single |  | Purchase | SMT | 15 | PCS | LED1 LED10 LED11 LED12 LED13 LED14 LED15 LED2 LED3 LED4 LED5 LED6 LED7 LED8 LED9 |
| 2 | 55.B0707.S06G | 84.02003.A37 | FET MOS P2003EVG PC SO-8 | R2_SA;HF_SA; | Released | NIKO | P2003EVG | Single |  | Purchase | SMT | 15 | PCS | U11 U14 U17 U2 U20 U23 U26 U29 U32 U35 U38 U41 U44 U5 U8 |
| 2 | 55.B0707.S06G | 84.03904.L06 | XTOR PMBS3904 NPN SOT23 (GP) | R2_SA;HF_SA;G_SA; | Released | NXP | PMBS3904 | Single |  | Purchase | SMT | 15 | PCS | Q34 Q35 Q36 Q37 Q38 Q39 Q40 Q41 Q42 Q43 Q44 Q45 Q46 Q47 Q48 |
| 2 | 55.B0707.S06G | 84.04406.B37 | FET MOS AO4406AL NC SO-8(HF) | R2_SA;HF_SA;G_SA; | Released | AOS | AO4406AL | Single |  | Purchase | SMT | 15 | PCS | Q11 Q13 Q15 Q17 Q19 Q2 Q21 Q23 Q25 Q27 Q29 Q3 Q5 Q7 Q9 |
| 2 | 55.B0707.S06G | 84.27002.C3F | FET MOS 2N7002DW-7-F NC SOT363 | R2_SA;HF_SA; | Released | DIODES | 2N7002DW-7-F | Single |  | Purchase | SMT | 30 | PCS | Q1 Q10 Q12 Q14 Q16 Q18 Q20 Q22 Q24 Q26 Q28 Q30 Q31 Q32 Q33 Q4 Q52 Q54 Q56 Q58 Q6 Q60 Q62 Q64 Q66 Q68 Q70 Q72 Q74 Q8 |
| 2 | 55.B0707.S06G | 84.27002.W31 | FET MOS 2N7002 NC SOT-23 | R2_SA;HF_SA;G_SA; | Released | PANJIT | 2N7002 | Single |  | Purchase | SMT | 15 | PCS | Q49 Q50 Q51 Q53 Q55 Q57 Q59 Q61 Q63 Q65 Q67 Q69 Q71 Q73 Q75 |
